# S9S_MB_2U (Grand Teton) — schematic netlist excerpt (pin names and nets, part order shuffled) for the footprints in the layout excerpt that follows; sources: Cadence DE-HDL packaged netlist, KiCad conversion of 03242023_DA0F0TMBIJ0_F0T_Motherboard_J_brd_V01_OCP.brd

U2_DC  TP  NA  pkg TP_BOM ONLY  page 312 : TP = NC
C230  Q_CAP  47UF 4V 20% X6S  pkg C0805  page 77 : A = PVCCIN_CPU1 ; B = GND
R4482  Q_RES  49.9 1% EMPTY  pkg 0402LF  page 152 : A = USB2_HOST_BMC_B_BUF_DP ; B = GND
R1754  Q_RES  33.2 1% CHIP  pkg 0402LF  page 222 : A = SGPIO_LD_0 ; B = SGPIO_DEBUG_PLD_LD_N

(kicad_pcb
	(version 20260206)
	(generator "pcbnew")
	(generator_version "10.0")
	(general
		(thickness 1.6)
		(legacy_teardrops no)
	)
	(paper "A4")
	(title_block
		(title "03242023_DA0F0TMBIJ0_F0T_Motherboard_J_brd_V01_OCP.brd")
		(comment 1 "Grand Teton / footprints 901-904 of 6105")
	)
	(layers
		(0 "F.Cu" signal "TOP")
		(4 "In1.Cu" signal "GND")
		(6 "In2.Cu" signal "IN1")
		(8 "In3.Cu" signal "GND1")
		(10 "In4.Cu" signal "IN2")
		(12 "In5.Cu" signal "GND2")
		(14 "In6.Cu" signal "IN3")
		(16 "In7.Cu" signal "GND3")
		(18 "In8.Cu" signal "VCC")
		(20 "In9.Cu" signal "VCC1")
		(22 "In10.Cu" signal "GND4")
		(24 "In11.Cu" signal "IN4")
		(26 "In12.Cu" signal "GND5")
		(28 "In13.Cu" signal "IN5")
		(30 "In14.Cu" signal "GND6")
		(32 "In15.Cu" signal "IN6")
		(34 "In16.Cu" signal "GND7")
		(2 "B.Cu" signal "BOTTOM")
		(9 "F.Adhes" user "F.Adhesive")
		(11 "B.Adhes" user "B.Adhesive")
		(13 "F.Paste" user "Package Geometry/Pastemask Top")
		(15 "B.Paste" user "Package Geometry/Pastemask Bottom")
		(5 "F.SilkS" user "Ref Des/Silkscreen Top")
		(7 "B.SilkS" user "Ref Des/Silkscreen Bottom")
		(1 "F.Mask" user "Board Geometry/Soldermask Top")
		(3 "B.Mask" user "Board Geometry/Soldermask Bottom")
		(17 "Dwgs.User" user "User.Drawings")
		(19 "Cmts.User" user "User.Comments")
		(21 "Eco1.User" user "User.Eco1")
		(23 "Eco2.User" user "User.Eco2")
		(25 "Edge.Cuts" user "Board Geometry/Outline")
		(27 "Margin" user)
		(31 "F.CrtYd" user "Package Geometry/Place Bound Top")
		(29 "B.CrtYd" user "Package Geometry/Place Bound Bottom")
		(35 "F.Fab" user "Ref Des/Assembly Top")
		(33 "B.Fab" user "Ref Des/Assembly Bottom")
	)
	(footprint ""
		(layer "F.Cu")
		(at 161.163 -99.786948)
		(property "Reference" "R1754"
			(at 0 0 0)
			(layer "F.SilkS")
			(hide yes)
			(effects
				(font
					(size 1.27 1.27)
				)
			)
		)
		(property "Value" ""
			(at 0 0 0)
			(layer "F.Fab")
			(effects
				(font
					(size 1.27 1.27)
				)
			)
		)
		(duplicate_pad_numbers_are_jumpers no)
		(fp_line
			(start -0.7874 -0.4064)
			(end 0.7874 -0.4064)
			(stroke
				(width 0.1524)
				(type default)
			)
			(layer "F.SilkS")
		)
		(fp_line
			(start -0.7874 0.4064)
			(end -0.7874 -0.4064)
			(stroke
				(width 0.1524)
				(type default)
			)
			(layer "F.SilkS")
		)
		(fp_line
			(start 0.7874 -0.4064)
			(end 0.7874 0.4064)
			(stroke
				(width 0.1524)
				(type default)
			)
			(layer "F.SilkS")
		)
		(fp_line
			(start 0.7874 0.4064)
			(end -0.7874 0.4064)
			(stroke
				(width 0.1524)
				(type default)
			)
			(layer "F.SilkS")
		)
		(fp_line
			(start -0.67945 -0.305054)
			(end -0.12065 -0.305054)
			(stroke
				(width 0.1)
				(type default)
			)
			(layer "F.Fab")
		)
		(fp_line
			(start -0.67945 0.3048)
			(end -0.67945 -0.305054)
			(stroke
				(width 0.1)
				(type default)
			)
			(layer "F.Fab")
		)
		(fp_line
			(start -0.12065 -0.305054)
			(end -0.12065 -0.2794)
			(stroke
				(width 0.1)
				(type default)
			)
			(layer "F.Fab")
		)
		(fp_line
			(start -0.12065 -0.2794)
			(end 0.12065 -0.2794)
			(stroke
				(width 0.1)
				(type default)
			)
			(layer "F.Fab")
		)
		(fp_line
			(start -0.12065 0.2794)
			(end -0.12065 0.3048)
			(stroke
				(width 0.1)
				(type default)
			)
			(layer "F.Fab")
		)
		(fp_line
			(start -0.12065 0.3048)
			(end -0.67945 0.3048)
			(stroke
				(width 0.1)
				(type default)
			)
			(layer "F.Fab")
		)
		(fp_line
			(start 0.120396 0.2794)
			(end -0.12065 0.2794)
			(stroke
				(width 0.1)
				(type default)
			)
			(layer "F.Fab")
		)
		(fp_line
			(start 0.120396 0.3048)
			(end 0.120396 0.2794)
			(stroke
				(width 0.1)
				(type default)
			)
			(layer "F.Fab")
		)
		(fp_line
			(start 0.12065 -0.3048)
			(end 0.67945 -0.3048)
			(stroke
				(width 0.1)
				(type default)
			)
			(layer "F.Fab")
		)
		(fp_line
			(start 0.12065 -0.2794)
			(end 0.12065 -0.3048)
			(stroke
				(width 0.1)
				(type default)
			)
			(layer "F.Fab")
		)
		(fp_line
			(start 0.67945 -0.3048)
			(end 0.67945 0.3048)
			(stroke
				(width 0.1)
				(type default)
			)
			(layer "F.Fab")
		)
		(fp_line
			(start 0.67945 0.3048)
			(end 0.120396 0.3048)
			(stroke
				(width 0.1)
				(type default)
			)
			(layer "F.Fab")
		)
		(pad "1" smd circle
			(at -0.40005 0)
			(size 0 0)
			(layers "F.Cu" "F.Mask" "F.Paste")
			(net "SGPIO_LD_0")
		)
		(pad "2" smd circle
			(at 0.40005 0)
			(size 0 0)
			(layers "F.Cu" "F.Mask" "F.Paste")
			(net "SGPIO_DEBUG_PLD_LD_N")
		)
	)
	(footprint ""
		(layer "F.Cu")
		(at 14.886178 -107.123484 180)
		(property "Reference" "R4482"
			(at 0 0 180)
			(layer "F.SilkS")
			(hide yes)
			(effects
				(font
					(size 1.27 1.27)
				)
			)
		)
		(property "Value" ""
			(at 0 0 180)
			(layer "F.Fab")
			(effects
				(font
					(size 1.27 1.27)
				)
			)
		)
		(duplicate_pad_numbers_are_jumpers no)
		(fp_line
			(start 0.7874 0.4064)
			(end -0.013462 0.4064)
			(stroke
				(width 0.1524)
				(type default)
			)
			(layer "F.SilkS")
		)
		(fp_line
			(start 0.7874 -0.4064)
			(end 0.7874 0.4064)
			(stroke
				(width 0.1524)
				(type default)
			)
			(layer "F.SilkS")
		)
		(fp_line
			(start -0.003302 -0.4064)
			(end 0.7874 -0.4064)
			(stroke
				(width 0.1524)
				(type default)
			)
			(layer "F.SilkS")
		)
		(fp_line
			(start 0.67945 0.3048)
			(end 0.120396 0.3048)
			(stroke
				(width 0.1)
				(type default)
			)
			(layer "F.Fab")
		)
		(fp_line
			(start 0.67945 -0.3048)
			(end 0.67945 0.3048)
			(stroke
				(width 0.1)
				(type default)
			)
			(layer "F.Fab")
		)
		(fp_line
			(start 0.12065 -0.2794)
			(end 0.12065 -0.3048)
			(stroke
				(width 0.1)
				(type default)
			)
			(layer "F.Fab")
		)
		(fp_line
			(start 0.12065 -0.3048)
			(end 0.67945 -0.3048)
			(stroke
				(width 0.1)
				(type default)
			)
			(layer "F.Fab")
		)
		(fp_line
			(start 0.120396 0.3048)
			(end 0.120396 0.2794)
			(stroke
				(width 0.1)
				(type default)
			)
			(layer "F.Fab")
		)
		(fp_line
			(start 0.120396 0.2794)
			(end -0.12065 0.2794)
			(stroke
				(width 0.1)
				(type default)
			)
			(layer "F.Fab")
		)
		(fp_line
			(start -0.12065 0.3048)
			(end -0.67945 0.3048)
			(stroke
				(width 0.1)
				(type default)
			)
			(layer "F.Fab")
		)
		(fp_line
			(start -0.12065 0.2794)
			(end -0.12065 0.3048)
			(stroke
				(width 0.1)
				(type default)
			)
			(layer "F.Fab")
		)
		(fp_line
			(start -0.12065 -0.2794)
			(end 0.12065 -0.2794)
			(stroke
				(width 0.1)
				(type default)
			)
			(layer "F.Fab")
		)
		(fp_line
			(start -0.12065 -0.305054)
			(end -0.12065 -0.2794)
			(stroke
				(width 0.1)
				(type default)
			)
			(layer "F.Fab")
		)
		(fp_line
			(start -0.67945 0.3048)
			(end -0.67945 -0.305054)
			(stroke
				(width 0.1)
				(type default)
			)
			(layer "F.Fab")
		)
		(fp_line
			(start -0.67945 -0.305054)
			(end -0.12065 -0.305054)
			(stroke
				(width 0.1)
				(type default)
			)
			(layer "F.Fab")
		)
		(pad "1" smd circle
			(at -0.40005 0 180)
			(size 0 0)
			(layers "F.Cu" "F.Mask" "F.Paste")
			(net "USB2_HOST_BMC_B_BUF_DP")
		)
		(pad "2" smd circle
			(at 0.40005 0 180)
			(size 0 0)
			(layers "F.Cu" "F.Mask" "F.Paste")
			(net "GND")
		)
	)
	(footprint ""
		(layer "F.Cu")
		(at 488.89793 -467.88705)
		(property "Reference" "U2_DC"
			(at -3.00355 1.898142 0)
			(unlocked yes)
			(layer "F.SilkS")
			(effects
				(font
					(size 0.7874 0.5842)
					(thickness 0.1524)
				)
				(justify left)
			)
		)
		(property "Value" ""
			(at 0 0 0)
			(layer "F.Fab")
			(effects
				(font
					(size 1.27 1.27)
				)
			)
		)
		(duplicate_pad_numbers_are_jumpers no)
		(pad "1" smd circle
			(at 0 0)
			(size 0.762 0.762)
			(layers "F.Cu" "F.Mask" "F.Paste")
			(net "Net_8483")
		)
	)
	(footprint ""
		(layer "F.Cu")
		(at 111.74222 -294.01008 180)
		(property "Reference" "C230"
			(at 0 0 180)
			(layer "F.SilkS")
			(hide yes)
			(effects
				(font
					(size 1.27 1.27)
				)
			)
		)
		(property "Value" ""
			(at 0 0 180)
			(layer "F.Fab")
			(effects
				(font
					(size 1.27 1.27)
				)
			)
		)
		(duplicate_pad_numbers_are_jumpers no)
		(fp_line
			(start 1.524 0.762)
			(end -1.524 0.762)
			(stroke
				(width 0.1524)
				(type default)
			)
			(layer "F.SilkS")
		)
		(fp_line
			(start 1.524 -0.762)
			(end 1.524 0.762)
			(stroke
				(width 0.1524)
				(type default)
			)
			(layer "F.SilkS")
		)
		(fp_line
			(start -1.524 0.762)
			(end -1.524 -0.762)
			(stroke
				(width 0.1524)
				(type default)
			)
			(layer "F.SilkS")
		)
		(fp_line
			(start -1.524 -0.762)
			(end 1.524 -0.762)
			(stroke
				(width 0.1524)
				(type default)
			)
			(layer "F.SilkS")
		)
		(fp_line
			(start 1.1049 0.724916)
			(end 1.1049 -0.724916)
			(stroke
				(width 0.1)
				(type default)
			)
			(layer "F.Fab")
		)
		(fp_line
			(start 1.1049 -0.724916)
			(end -1.1049 -0.724916)
			(stroke
				(width 0.1)
				(type default)
			)
			(layer "F.Fab")
		)
		(fp_line
			(start -1.1049 0.724916)
			(end 1.1049 0.724916)
			(stroke
				(width 0.1)
				(type default)
			)
			(layer "F.Fab")
		)
		(fp_line
			(start -1.1049 -0.724916)
			(end -1.1049 0.724916)
			(stroke
				(width 0.1)
				(type default)
			)
			(layer "F.Fab")
		)
		(pad "1" smd rect
			(at -0.889 0)
			(size 1.016 1.27)
			(layers "F.Cu" "F.Mask" "F.Paste")
			(net "PVCCIN_CPU1")
		)
		(pad "2" smd rect
			(at 0.889 0)
			(size 1.016 1.27)
			(layers "F.Cu" "F.Mask" "F.Paste")
			(net "GND")
		)
	)
)
